(kicad_pcb
	(version 20241229)
	(generator "pcbnew")
	(generator_version "9.0")
	(general
		(thickness 1.61)
		(legacy_teardrops no)
	)
	(paper "A3")
	(title_block
		(title "RDIMM DDR5 Tester")
		(date "2026-05-21")
		(rev "2.2.0")
		(company "Antmicro")
		(comment 9 "footprints 585-589 of 796")
	)
	(layers
		(0 "F.Cu" signal)
		(4 "In1.Cu" power)
		(6 "In2.Cu" mixed)
		(8 "In3.Cu" power)
		(10 "In4.Cu" mixed)
		(12 "In5.Cu" power)
		(14 "In6.Cu" mixed)
		(16 "In7.Cu" power)
		(18 "In8.Cu" power)
		(20 "In9.Cu" mixed)
		(22 "In10.Cu" power)
		(2 "B.Cu" signal)
		(9 "F.Adhes" user "F.Adhesive")
		(11 "B.Adhes" user "B.Adhesive")
		(13 "F.Paste" user)
		(15 "B.Paste" user)
		(5 "F.SilkS" user "F.Silkscreen")
		(7 "B.SilkS" user "B.Silkscreen")
		(1 "F.Mask" user)
		(3 "B.Mask" user)
		(17 "Dwgs.User" user "User.Drawings")
		(19 "Cmts.User" user "User.Comments")
		(21 "Eco1.User" user "User.Eco1")
		(23 "Eco2.User" user "User.Eco2")
		(25 "Edge.Cuts" user)
		(27 "Margin" user)
		(31 "F.CrtYd" user "F.Courtyard")
		(29 "B.CrtYd" user "B.Courtyard")
		(35 "F.Fab" user)
		(33 "B.Fab" user)
	)
	(footprint "antmicro-footprints:C_0402_1005Metric_EIA"
		(layer "B.Cu")
		(at 187 156.5 -90)
		(descr "Capacitor SMD 0402 (1005 Metric), square (rectangular) end terminal, IPC_7351 nominal, (Body size source: IPC-SM-782 page 76, https://www.pcb-3d.com/wordpress/wp-content/uploads/ipc-sm-782a_amendment_1_and_2.pdf)")
		(tags "capacitor 0402")
		(property "Reference" "C33"
			(at -11.925 30.625 90)
			(layer "B.SilkS")
			(effects
				(font
					(size 0.7 0.7)
					(thickness 0.15)
				)
				(justify left bottom mirror)
			)
		)
		(property "Value" "C_100n_0402"
			(at 0 -1.169 90)
			(layer "B.Fab")
			(effects
				(font
					(size 0.7 0.7)
					(thickness 0.15)
				)
				(justify left bottom mirror)
			)
		)
		(property "Datasheet" "https://www.murata.com/products/productdetail?partno=GRM155R61H104KE14%23"
			(at 0 0 270)
			(layer "F.Fab")
			(hide yes)
			(effects
				(font
					(size 1.27 1.27)
					(thickness 0.15)
				)
			)
		)
		(property "MPN" "GRM155R61H104KE14D"
			(at 0 0 270)
			(unlocked yes)
			(layer "B.Fab")
			(hide yes)
			(effects
				(font
					(size 1 1)
					(thickness 0.15)
				)
				(justify mirror)
			)
		)
		(property "Manufacturer" "Murata"
			(at 0 0 270)
			(unlocked yes)
			(layer "B.Fab")
			(hide yes)
			(effects
				(font
					(size 1 1)
					(thickness 0.15)
				)
				(justify mirror)
			)
		)
		(property "License" "Apache-2.0"
			(at 0 0 270)
			(unlocked yes)
			(layer "B.Fab")
			(hide yes)
			(effects
				(font
					(size 1 1)
					(thickness 0.15)
				)
				(justify mirror)
			)
		)
		(property "Author" "Antmicro"
			(at 0 0 270)
			(unlocked yes)
			(layer "B.Fab")
			(hide yes)
			(effects
				(font
					(size 1 1)
					(thickness 0.15)
				)
				(justify mirror)
			)
		)
		(property "Val" "100n"
			(at 0 0 270)
			(unlocked yes)
			(layer "B.Fab")
			(hide yes)
			(effects
				(font
					(size 1 1)
					(thickness 0.15)
				)
				(justify mirror)
			)
		)
		(property "Voltage" "50V"
			(at 0 0 270)
			(unlocked yes)
			(layer "B.Fab")
			(hide yes)
			(effects
				(font
					(size 1 1)
					(thickness 0.15)
				)
				(justify mirror)
			)
		)
		(property "Dielectric" "X5R"
			(at 0 0 270)
			(unlocked yes)
			(layer "B.Fab")
			(hide yes)
			(effects
				(font
					(size 1 1)
					(thickness 0.15)
				)
				(justify mirror)
			)
		)
		(sheetname "/FPGA power/")
		(sheetfile "fpga-power.kicad_sch")
		(attr smd)
		(fp_rect
			(start -0.95 0.45)
			(end 0.95 -0.45)
			(stroke
				(width 0.05)
				(type default)
			)
			(fill no)
			(layer "B.CrtYd")
		)
		(fp_line
			(start -0.5 0.25)
			(end 0.498 0.25)
			(stroke
				(width 0.15)
				(type solid)
			)
			(layer "B.Fab")
		)
		(fp_line
			(start 0.498 0.25)
			(end 0.498 -0.248)
			(stroke
				(width 0.15)
				(type solid)
			)
			(layer "B.Fab")
		)
		(fp_line
			(start -0.5 -0.248)
			(end -0.5 0.25)
			(stroke
				(width 0.15)
				(type solid)
			)
			(layer "B.Fab")
		)
		(fp_line
			(start 0.498 -0.248)
			(end -0.5 -0.248)
			(stroke
				(width 0.15)
				(type solid)
			)
			(layer "B.Fab")
		)
		(fp_text user "License: Apache-2.0"
			(at -0.9656 -4.369 90)
			(layer "B.Fab")
			(effects
				(font
					(size 0.7 0.7)
					(thickness 0.15)
				)
				(justify left bottom mirror)
			)
		)
		(fp_text user "Author: Antmicro"
			(at -0.9656 -5.569 90)
			(layer "B.Fab")
			(effects
				(font
					(size 0.7 0.7)
					(thickness 0.15)
				)
				(justify left bottom mirror)
			)
		)
		(fp_text user "${REFERENCE}"
			(at -0.9656 -3.169 90)
			(layer "B.Fab")
			(effects
				(font
					(size 0.7 0.7)
					(thickness 0.15)
				)
				(justify left bottom mirror)
			)
		)
		(pad "1" smd roundrect
			(at -0.5 0 180)
			(size 0.6 0.6)
			(layers "B.Cu" "B.Mask" "B.Paste")
			(roundrect_rratio 0.25)
			(net 1 "GND")
			(pintype "passive")
		)
		(pad "2" smd roundrect
			(at 0.498 0 270)
			(size 0.6 0.6)
			(layers "B.Cu" "B.Mask" "B.Paste")
			(roundrect_rratio 0.25)
			(net 553 "+0V85")
			(pintype "passive")
		)
	)
	(footprint "antmicro-footprints:C_0402_1005Metric_EIA"
		(layer "B.Cu")
		(at 191.5 147 180)
		(descr "Capacitor SMD 0402 (1005 Metric), square (rectangular) end terminal, IPC_7351 nominal, (Body size source: IPC-SM-782 page 76, https://www.pcb-3d.com/wordpress/wp-content/uploads/ipc-sm-782a_amendment_1_and_2.pdf)")
		(tags "capacitor 0402")
		(property "Reference" "C30"
			(at 30 10.9 0)
			(layer "B.SilkS")
			(effects
				(font
					(size 0.7 0.7)
					(thickness 0.15)
				)
				(justify left bottom mirror)
			)
		)
		(property "Value" "C_10u_10V_0402"
			(at 0 -1.169 0)
			(layer "B.Fab")
			(effects
				(font
					(size 0.7 0.7)
					(thickness 0.15)
				)
				(justify left bottom mirror)
			)
		)
		(property "Datasheet" "https://www.murata.com/products/productdetail?partno=GRM155R61A106ME11%23"
			(at 0 0 180)
			(layer "F.Fab")
			(hide yes)
			(effects
				(font
					(size 1.27 1.27)
					(thickness 0.15)
				)
			)
		)
		(property "MPN" "GRM155R61A106ME11D"
			(at 0 0 180)
			(unlocked yes)
			(layer "B.Fab")
			(hide yes)
			(effects
				(font
					(size 1 1)
					(thickness 0.15)
				)
				(justify mirror)
			)
		)
		(property "Manufacturer" "Murata"
			(at 0 0 180)
			(unlocked yes)
			(layer "B.Fab")
			(hide yes)
			(effects
				(font
					(size 1 1)
					(thickness 0.15)
				)
				(justify mirror)
			)
		)
		(property "License" "Apache-2.0"
			(at 0 0 180)
			(unlocked yes)
			(layer "B.Fab")
			(hide yes)
			(effects
				(font
					(size 1 1)
					(thickness 0.15)
				)
				(justify mirror)
			)
		)
		(property "Author" "Antmicro"
			(at 0 0 180)
			(unlocked yes)
			(layer "B.Fab")
			(hide yes)
			(effects
				(font
					(size 1 1)
					(thickness 0.15)
				)
				(justify mirror)
			)
		)
		(property "Val" "10u"
			(at 0 0 180)
			(unlocked yes)
			(layer "B.Fab")
			(hide yes)
			(effects
				(font
					(size 1 1)
					(thickness 0.15)
				)
				(justify mirror)
			)
		)
		(property "Voltage" "10V"
			(at 0 0 180)
			(unlocked yes)
			(layer "B.Fab")
			(hide yes)
			(effects
				(font
					(size 1 1)
					(thickness 0.15)
				)
				(justify mirror)
			)
		)
		(property "Dielectric" "X5R"
			(at 0 0 180)
			(unlocked yes)
			(layer "B.Fab")
			(hide yes)
			(effects
				(font
					(size 1 1)
					(thickness 0.15)
				)
				(justify mirror)
			)
		)
		(sheetname "/FPGA power/")
		(sheetfile "fpga-power.kicad_sch")
		(attr smd)
		(fp_rect
			(start -0.95 0.45)
			(end 0.95 -0.45)
			(stroke
				(width 0.05)
				(type default)
			)
			(fill no)
			(layer "B.CrtYd")
		)
		(fp_line
			(start 0.498 0.25)
			(end 0.498 -0.248)
			(stroke
				(width 0.15)
				(type solid)
			)
			(layer "B.Fab")
		)
		(fp_line
			(start 0.498 -0.248)
			(end -0.5 -0.248)
			(stroke
				(width 0.15)
				(type solid)
			)
			(layer "B.Fab")
		)
		(fp_line
			(start -0.5 0.25)
			(end 0.498 0.25)
			(stroke
				(width 0.15)
				(type solid)
			)
			(layer "B.Fab")
		)
		(fp_line
			(start -0.5 -0.248)
			(end -0.5 0.25)
			(stroke
				(width 0.15)
				(type solid)
			)
			(layer "B.Fab")
		)
		(fp_text user "License: Apache-2.0"
			(at -0.9656 -4.369 0)
			(layer "B.Fab")
			(effects
				(font
					(size 0.7 0.7)
					(thickness 0.15)
				)
				(justify left bottom mirror)
			)
		)
		(fp_text user "Author: Antmicro"
			(at -0.9656 -5.569 0)
			(layer "B.Fab")
			(effects
				(font
					(size 0.7 0.7)
					(thickness 0.15)
				)
				(justify left bottom mirror)
			)
		)
		(fp_text user "${REFERENCE}"
			(at -0.9656 -3.169 0)
			(layer "B.Fab")
			(effects
				(font
					(size 0.7 0.7)
					(thickness 0.15)
				)
				(justify left bottom mirror)
			)
		)
		(pad "1" smd roundrect
			(at -0.5 0 90)
			(size 0.6 0.6)
			(layers "B.Cu" "B.Mask" "B.Paste")
			(roundrect_rratio 0.25)
			(net 1 "GND")
			(pintype "passive")
		)
		(pad "2" smd roundrect
			(at 0.498 0 180)
			(size 0.6 0.6)
			(layers "B.Cu" "B.Mask" "B.Paste")
			(roundrect_rratio 0.25)
			(net 797 "+1V8")
			(pintype "passive")
		)
	)
	(footprint "antmicro-footprints:C_0603_1608Metric"
		(layer "B.Cu")
		(at 162.725 154.3 -90)
		(descr "Capacitor SMD 0603")
		(tags "capacitor 0603")
		(property "Reference" "C1"
			(at -2.7 -0.375 90)
			(layer "B.SilkS")
			(effects
				(font
					(size 0.7 0.7)
					(thickness 0.15)
				)
				(justify left bottom mirror)
			)
		)
		(property "Value" "C_47u_0603"
			(at -1.42757 -1.770288 90)
			(layer "B.Fab")
			(effects
				(font
					(size 0.7 0.7)
					(thickness 0.15)
				)
				(justify left bottom mirror)
			)
		)
		(property "Datasheet" "https://www.murata.com/products/productdetail?partno=GRM188R60J476ME15%23"
			(at 0 0 270)
			(layer "F.Fab")
			(hide yes)
			(effects
				(font
					(size 1.27 1.27)
					(thickness 0.15)
				)
			)
		)
		(property "Manufacturer" "Murata"
			(at 0 0 270)
			(unlocked yes)
			(layer "B.Fab")
			(hide yes)
			(effects
				(font
					(size 1 1)
					(thickness 0.15)
				)
				(justify mirror)
			)
		)
		(property "MPN" "GRM188R60J476ME15D"
			(at 0 0 270)
			(unlocked yes)
			(layer "B.Fab")
			(hide yes)
			(effects
				(font
					(size 1 1)
					(thickness 0.15)
				)
				(justify mirror)
			)
		)
		(property "Val" "47u"
			(at 0 0 270)
			(unlocked yes)
			(layer "B.Fab")
			(hide yes)
			(effects
				(font
					(size 1 1)
					(thickness 0.15)
				)
				(justify mirror)
			)
		)
		(property "License" "Apache-2.0"
			(at 0 0 270)
			(unlocked yes)
			(layer "B.Fab")
			(hide yes)
			(effects
				(font
					(size 1 1)
					(thickness 0.15)
				)
				(justify mirror)
			)
		)
		(property "Author" "Antmicro"
			(at 0 0 270)
			(unlocked yes)
			(layer "B.Fab")
			(hide yes)
			(effects
				(font
					(size 1 1)
					(thickness 0.15)
				)
				(justify mirror)
			)
		)
		(property "Voltage" ""
			(at 0 0 270)
			(unlocked yes)
			(layer "B.Fab")
			(hide yes)
			(effects
				(font
					(size 1 1)
					(thickness 0.15)
				)
				(justify mirror)
			)
		)
		(property "Dielectric" ""
			(at 0 0 270)
			(unlocked yes)
			(layer "B.Fab")
			(hide yes)
			(effects
				(font
					(size 1 1)
					(thickness 0.15)
				)
				(justify mirror)
			)
		)
		(sheetname "/HyperRAM + QSPI Flash/")
		(sheetfile "hyperram-flash.kicad_sch")
		(attr smd)
		(fp_line
			(start -0.15 0.4)
			(end 0.15 0.4)
			(stroke
				(width 0.15)
				(type solid)
			)
			(layer "B.SilkS")
		)
		(fp_line
			(start -0.15 -0.4)
			(end 0.15 -0.4)
			(stroke
				(width 0.15)
				(type solid)
			)
			(layer "B.SilkS")
		)
		(fp_rect
			(start -1.25 0.65)
			(end 1.25 -0.65)
			(stroke
				(width 0.05)
				(type solid)
			)
			(fill no)
			(layer "B.CrtYd")
		)
		(fp_rect
			(start -0.8 0.4)
			(end 0.8 -0.4)
			(stroke
				(width 0.15)
				(type solid)
			)
			(fill no)
			(layer "B.Fab")
		)
		(fp_text user "License: Apache-2.0"
			(at -1.682 -5.895 90)
			(layer "B.Fab")
			(effects
				(font
					(size 0.7 0.7)
					(thickness 0.15)
				)
				(justify left bottom mirror)
			)
		)
		(fp_text user "Author: Antmicro"
			(at -1.682 -4.894 90)
			(layer "B.Fab")
			(effects
				(font
					(size 0.7 0.7)
					(thickness 0.15)
				)
				(justify left bottom mirror)
			)
		)
		(fp_text user "${REFERENCE}"
			(at -1.682 -3.895 90)
			(layer "B.Fab")
			(effects
				(font
					(size 0.7 0.7)
					(thickness 0.15)
				)
				(justify left bottom mirror)
			)
		)
		(pad "1" smd roundrect
			(at -0.7 0 270)
			(size 0.8 1)
			(layers "B.Cu" "B.Mask" "B.Paste")
			(roundrect_rratio 0.2)
			(net 797 "+1V8")
			(pintype "passive")
		)
		(pad "2" smd roundrect
			(at 0.7 0 270)
			(size 0.8 1)
			(layers "B.Cu" "B.Mask" "B.Paste")
			(roundrect_rratio 0.2)
			(net 1 "GND")
			(pintype "passive")
		)
	)
	(footprint "antmicro-footprints:C_0402_1005Metric"
		(layer "B.Cu")
		(at 252.2 187.338)
		(descr "Capacitor SMD 0402")
		(tags "capacitor SMD 0402")
		(property "Reference" "C324"
			(at 1 0.449 0)
			(layer "B.SilkS")
			(effects
				(font
					(size 0.7 0.7)
					(thickness 0.15)
				)
				(justify right bottom mirror)
			)
		)
		(property "Value" "C_100n_0402"
			(at -1.022927 -2.155213 0)
			(layer "B.Fab")
			(effects
				(font
					(size 0.7 0.7)
					(thickness 0.15)
				)
				(justify right bottom mirror)
			)
		)
		(property "Datasheet" "https://www.murata.com/products/productdetail?partno=GRM155R61H104KE14%23"
			(at 0 0 0)
			(layer "F.Fab")
			(hide yes)
			(effects
				(font
					(size 1.27 1.27)
					(thickness 0.15)
				)
			)
		)
		(property "MPN" "GRM155R61H104KE14D"
			(at 0 0 0)
			(unlocked yes)
			(layer "B.Fab")
			(hide yes)
			(effects
				(font
					(size 1 1)
					(thickness 0.15)
				)
				(justify mirror)
			)
		)
		(property "Manufacturer" "Murata"
			(at 0 0 0)
			(unlocked yes)
			(layer "B.Fab")
			(hide yes)
			(effects
				(font
					(size 1 1)
					(thickness 0.15)
				)
				(justify mirror)
			)
		)
		(property "License" "Apache-2.0"
			(at 0 0 0)
			(unlocked yes)
			(layer "B.Fab")
			(hide yes)
			(effects
				(font
					(size 1 1)
					(thickness 0.15)
				)
				(justify mirror)
			)
		)
		(property "Author" "Antmicro"
			(at 0 0 0)
			(unlocked yes)
			(layer "B.Fab")
			(hide yes)
			(effects
				(font
					(size 1 1)
					(thickness 0.15)
				)
				(justify mirror)
			)
		)
		(property "Val" "100n"
			(at 0 0 0)
			(unlocked yes)
			(layer "B.Fab")
			(hide yes)
			(effects
				(font
					(size 1 1)
					(thickness 0.15)
				)
				(justify mirror)
			)
		)
		(property "Voltage" "50V"
			(at 0 0 0)
			(unlocked yes)
			(layer "B.Fab")
			(hide yes)
			(effects
				(font
					(size 1 1)
					(thickness 0.15)
				)
				(justify mirror)
			)
		)
		(property "Dielectric" "X5R"
			(at 0 0 0)
			(unlocked yes)
			(layer "B.Fab")
			(hide yes)
			(effects
				(font
					(size 1 1)
					(thickness 0.15)
				)
				(justify mirror)
			)
		)
		(sheetname "/I^{2}C + I3C/")
		(sheetfile "i2c.kicad_sch")
		(attr smd)
		(fp_rect
			(start -0.925 0.47)
			(end 0.925 -0.47)
			(stroke
				(width 0.05)
				(type default)
			)
			(fill no)
			(layer "B.CrtYd")
		)
		(fp_line
			(start -0.494 -0.248)
			(end -0.494 0.25)
			(stroke
				(width 0.15)
				(type solid)
			)
			(layer "B.Fab")
		)
		(fp_line
			(start -0.494 0.25)
			(end 0.504 0.25)
			(stroke
				(width 0.15)
				(type solid)
			)
			(layer "B.Fab")
		)
		(fp_line
			(start 0.504 -0.248)
			(end -0.494 -0.248)
			(stroke
				(width 0.15)
				(type solid)
			)
			(layer "B.Fab")
		)
		(fp_line
			(start 0.504 0.25)
			(end 0.504 -0.248)
			(stroke
				(width 0.15)
				(type solid)
			)
			(layer "B.Fab")
		)
		(fp_text user "${REFERENCE}"
			(at -0.939 -4.599 180)
			(layer "B.Fab")
			(effects
				(font
					(size 0.7 0.7)
					(thickness 0.15)
				)
				(justify left bottom mirror)
			)
		)
		(fp_text user "Author: Antmicro"
			(at -0.939 -3.399 180)
			(layer "B.Fab")
			(effects
				(font
					(size 0.7 0.7)
					(thickness 0.15)
				)
				(justify left bottom mirror)
			)
		)
		(fp_text user "License: Apache-2.0"
			(at -0.939 -5.799 180)
			(layer "B.Fab")
			(effects
				(font
					(size 0.7 0.7)
					(thickness 0.15)
				)
				(justify left bottom mirror)
			)
		)
		(pad "1" smd roundrect
			(at -0.48 0)
			(size 0.59 0.64)
			(layers "B.Cu" "B.Mask" "B.Paste")
			(roundrect_rratio 0.25)
			(net 1 "GND")
			(pintype "passive")
		)
		(pad "2" smd roundrect
			(at 0.48 0)
			(size 0.59 0.64)
			(layers "B.Cu" "B.Mask" "B.Paste")
			(roundrect_rratio 0.25)
			(net 782 "Net-(Q24-D)")
			(pintype "passive")
		)
	)
	(footprint "antmicro-footprints:C_0402_1005Metric_EIA"
		(layer "B.Cu")
		(at 191 158.5 90)
		(descr "Capacitor SMD 0402 (1005 Metric), square (rectangular) end terminal, IPC_7351 nominal, (Body size source: IPC-SM-782 page 76, https://www.pcb-3d.com/wordpress/wp-content/uploads/ipc-sm-782a_amendment_1_and_2.pdf)")
		(tags "capacitor 0402")
		(property "Reference" "C248"
			(at 9.225 -30.6 90)
			(layer "B.SilkS")
			(effects
				(font
					(size 0.7 0.7)
					(thickness 0.15)
				)
				(justify right bottom mirror)
			)
		)
		(property "Value" "C_1u_25V_0402"
			(at 0 -1.169 90)
			(layer "B.Fab")
			(effects
				(font
					(size 0.7 0.7)
					(thickness 0.15)
				)
				(justify right bottom mirror)
			)
		)
		(property "Datasheet" "https://www.murata.com/products/productdetail?partno=GRM155R61E105KE11%23"
			(at 0 0 90)
			(layer "F.Fab")
			(hide yes)
			(effects
				(font
					(size 1.27 1.27)
					(thickness 0.15)
				)
			)
		)
		(property "MPN" "GRM155R61E105KE11J"
			(at 0 0 90)
			(unlocked yes)
			(layer "B.Fab")
			(hide yes)
			(effects
				(font
					(size 1 1)
					(thickness 0.15)
				)
				(justify mirror)
			)
		)
		(property "Manufacturer" "Murata"
			(at 0 0 90)
			(unlocked yes)
			(layer "B.Fab")
			(hide yes)
			(effects
				(font
					(size 1 1)
					(thickness 0.15)
				)
				(justify mirror)
			)
		)
		(property "License" "Apache-2.0"
			(at 0 0 90)
			(unlocked yes)
			(layer "B.Fab")
			(hide yes)
			(effects
				(font
					(size 1 1)
					(thickness 0.15)
				)
				(justify mirror)
			)
		)
		(property "Author" "Antmicro"
			(at 0 0 90)
			(unlocked yes)
			(layer "B.Fab")
			(hide yes)
			(effects
				(font
					(size 1 1)
					(thickness 0.15)
				)
				(justify mirror)
			)
		)
		(property "Val" "1u"
			(at 0 0 90)
			(unlocked yes)
			(layer "B.Fab")
			(hide yes)
			(effects
				(font
					(size 1 1)
					(thickness 0.15)
				)
				(justify mirror)
			)
		)
		(property "Voltage" "25V"
			(at 0 0 90)
			(unlocked yes)
			(layer "B.Fab")
			(hide yes)
			(effects
				(font
					(size 1 1)
					(thickness 0.15)
				)
				(justify mirror)
			)
		)
		(property "Dielectric" "X5R"
			(at 0 0 90)
			(unlocked yes)
			(layer "B.Fab")
			(hide yes)
			(effects
				(font
					(size 1 1)
					(thickness 0.15)
				)
				(justify mirror)
			)
		)
		(sheetname "/FPGA power/")
		(sheetfile "fpga-power.kicad_sch")
		(attr smd)
		(fp_rect
			(start -0.95 0.45)
			(end 0.95 -0.45)
			(stroke
				(width 0.05)
				(type default)
			)
			(fill no)
			(layer "B.CrtYd")
		)
		(fp_line
			(start 0.498 -0.248)
			(end -0.5 -0.248)
			(stroke
				(width 0.15)
				(type solid)
			)
			(layer "B.Fab")
		)
		(fp_line
			(start -0.5 -0.248)
			(end -0.5 0.25)
			(stroke
				(width 0.15)
				(type solid)
			)
			(layer "B.Fab")
		)
		(fp_line
			(start 0.498 0.25)
			(end 0.498 -0.248)
			(stroke
				(width 0.15)
				(type solid)
			)
			(layer "B.Fab")
		)
		(fp_line
			(start -0.5 0.25)
			(end 0.498 0.25)
			(stroke
				(width 0.15)
				(type solid)
			)
			(layer "B.Fab")
		)
		(fp_text user "${REFERENCE}"
			(at -0.9656 -3.169 270)
			(layer "B.Fab")
			(effects
				(font
					(size 0.7 0.7)
					(thickness 0.15)
				)
				(justify left bottom mirror)
			)
		)
		(fp_text user "Author: Antmicro"
			(at -0.9656 -5.569 270)
			(layer "B.Fab")
			(effects
				(font
					(size 0.7 0.7)
					(thickness 0.15)
				)
				(justify left bottom mirror)
			)
		)
		(fp_text user "License: Apache-2.0"
			(at -0.9656 -4.369 270)
			(layer "B.Fab")
			(effects
				(font
					(size 0.7 0.7)
					(thickness 0.15)
				)
				(justify left bottom mirror)
			)
		)
		(pad "1" smd roundrect
			(at -0.5 0)
			(size 0.6 0.6)
			(layers "B.Cu" "B.Mask" "B.Paste")
			(roundrect_rratio 0.25)
			(net 1 "GND")
			(pintype "passive")
		)
		(pad "2" smd roundrect
			(at 0.498 0 90)
			(size 0.6 0.6)
			(layers "B.Cu" "B.Mask" "B.Paste")
			(roundrect_rratio 0.25)
			(net 553 "+0V85")
			(pintype "passive")
		)
	)
)
